# S9S_MB_2U (Grand Teton) — schematic netlist excerpt (pin names and nets, part order shuffled) for the footprints in the layout excerpt that follows; sources: Cadence DE-HDL packaged netlist, KiCad conversion of 03242023_DA0F0TMBIJ0_F0T_Motherboard_J_brd_V01_OCP.brd

J59  SCONN75K_APCI0155P004A  SCONN75K_APCI0155-P004A EMPTY  pkg CON_F67S2H2D2S_P0-5W7-55_LUVXB_H270  page 190
  GND1  = PCIE_M2_SSD0_PRSNT_N
  \3.3v_1\  = P3V3_M2_0
  GND2  = GND
  \3.3v_2\  = P3V3_M2_0
  PERN3  = P3E_PCH_M2_RX_DN<0>
  NC1  = NC_M2_0_NC1
  PERP3  = P3E_PCH_M2_RX_DP<0>
  NC2  = NC_M2_0_NC2
  GND3  = GND
  \das_dss#||led1#\  = LED_M2_SSD_0_ACT_N
  PETN3  = P3E_PCH_M2_TX_C_DP<0>
  \3.3v_3\  = P3V3_M2_0
  PETP3  = P3E_PCH_M2_TX_C_DN<0>
  \3.3v_4\  = P3V3_M2_0
  GND4  = GND
  \3.3v_5\  = P3V3_M2_0
  PERN2  = P3E_PCH_M2_RX_DN<1>
  \3.3v_6\  = P3V3_M2_0
  PERP2  = P3E_PCH_M2_RX_DP<1>
  NC3  = NC_M2_0_NC3
  GND5  = GND
  NC4  = NC_M2_0_NC4
  PETN2  = P3E_PCH_M2_TX_C_DP<1>
  NC5  = NC_M2_0_NC5
  PETP2  = P3E_PCH_M2_TX_C_DN<1>
  NC6  = NC_M2_0_NC6
  GND6  = GND
  NC7  = NC_M2_0_NC7
  PERN1  = P3E_PCH_M2_RX_DN<2>
  NC8  = NC_M2_0_NC8
  PERP1  = P3E_PCH_M2_RX_DP<2>
  NC9  = NC_M2_0_NC9
  GND7  = GND
  NC10  = NC_M2_0_NC10
  PETN1  = P3E_PCH_M2_TX_C_DP<2>
  NC11  = NC_M2_0_NC11
  PETP1  = P3E_PCH_M2_TX_C_DN<2>
  DEVSLP  = PD_M2_0_DEVSLP
  GND8  = GND
  NC12  = SMB_M2_P0_1V8AUX_SCL
  \pern0||sata-b+\  = P3E_PCH_M2_RX_DN<3>
  NC13  = SMB_M2_P0_1V8AUX_SDA
  \perp0||sata-b-\  = P3E_PCH_M2_RX_DP<3>
  NC14  = NC_M2_0_NC14
  GND9  = GND
  NC15  = NC_M2_0_NC15
  \petn0||sata-a-\  = P3E_PCH_M2_TX_C_DP<3>
  NC16  = NC_M2_0_NC16
  \petp0||sata-a+\  = P3E_PCH_M2_TX_C_DN<3>
  \perst#\  = RST_PCIE_PCH_DEV_0_N
  GND10  = GND
  \clkreq#\  = M2_SSD0_CLKREQ_EN_N_BUF
  REFCLKN  = CLK_100M_PE_M2_0_DN
  \pewake#\  = M2_0_PEWAKE_N
  REFCLKP  = CLK_100M_PE_M2_0_DP
  NC17  = NC_M2_0_NC17
  GND11  = GND
  NC18  = NC_M2_0_NC18
  NC19  = NC_M2_0_NC19
  SUSCLK  = NC_M2_0_SUSCLK
  PEDET  = FM_M2_SSD_0_PEDET
  \3.3v_7\  = P3V3_M2_0
  GND12  = GND
  \3.3v_8\  = P3V3_M2_0
  GND13  = GND
  \3.3v_9\  = P3V3_M2_0
  GND14  = GND
  G1  = GND
  G2  = GND

(kicad_pcb
	(version 20260206)
	(generator "pcbnew")
	(generator_version "10.0")
	(general
		(thickness 1.6)
		(legacy_teardrops no)
	)
	(paper "A4")
	(title_block
		(title "03242023_DA0F0TMBIJ0_F0T_Motherboard_J_brd_V01_OCP.brd")
		(comment 1 "Grand Teton / footprint 3483 of 6105 (J59), pads 45-71 of 71")
	)
	(layers
		(0 "F.Cu" signal "TOP")
		(4 "In1.Cu" signal "GND")
		(6 "In2.Cu" signal "IN1")
		(8 "In3.Cu" signal "GND1")
		(10 "In4.Cu" signal "IN2")
		(12 "In5.Cu" signal "GND2")
		(14 "In6.Cu" signal "IN3")
		(16 "In7.Cu" signal "GND3")
		(18 "In8.Cu" signal "VCC")
		(20 "In9.Cu" signal "VCC1")
		(22 "In10.Cu" signal "GND4")
		(24 "In11.Cu" signal "IN4")
		(26 "In12.Cu" signal "GND5")
		(28 "In13.Cu" signal "IN5")
		(30 "In14.Cu" signal "GND6")
		(32 "In15.Cu" signal "IN6")
		(34 "In16.Cu" signal "GND7")
		(2 "B.Cu" signal "BOTTOM")
		(9 "F.Adhes" user "F.Adhesive")
		(11 "B.Adhes" user "B.Adhesive")
		(13 "F.Paste" user "Package Geometry/Pastemask Top")
		(15 "B.Paste" user "Package Geometry/Pastemask Bottom")
		(5 "F.SilkS" user "Ref Des/Silkscreen Top")
		(7 "B.SilkS" user "Ref Des/Silkscreen Bottom")
		(1 "F.Mask" user "Board Geometry/Soldermask Top")
		(3 "B.Mask" user "Board Geometry/Soldermask Bottom")
		(17 "Dwgs.User" user "User.Drawings")
		(19 "Cmts.User" user "User.Comments")
		(21 "Eco1.User" user "User.Eco1")
		(23 "Eco2.User" user "User.Eco2")
		(25 "Edge.Cuts" user "Board Geometry/Outline")
		(27 "Margin" user)
		(31 "F.CrtYd" user "Package Geometry/Place Bound Top")
		(29 "B.CrtYd" user "Package Geometry/Place Bound Bottom")
		(35 "F.Fab" user "Ref Des/Assembly Top")
		(33 "B.Fab" user "Ref Des/Assembly Bottom")
	)
	(footprint ""
		(layer "F.Cu")
		(at 173.358048 -47.049944)
		(property "Reference" "J59"
			(at 5.590032 -12.227814 0)
			(unlocked yes)
			(layer "F.SilkS")
			(effects
				(font
					(size 0.7874 0.5842)
					(thickness 0.1524)
				)
				(justify left)
			)
		)
		(property "Value" ""
			(at 0 0 0)
			(layer "F.Fab")
			(effects
				(font
					(size 1.27 1.27)
				)
			)
		)
		(duplicate_pad_numbers_are_jumpers no)
		(pad "43" smd rect
			(at 3.750056 1.249934 270)
			(size 0.2794 1.6002)
			(layers "F.Cu" "F.Mask" "F.Paste")
			(net "P3E_PCH_M2_RX_DP<3>")
		)
		(pad "44" smd rect
			(at -3.800094 1.500124 270)
			(size 0.2794 1.6002)
			(layers "F.Cu" "F.Mask" "F.Paste")
			(net "NC_M2_0_NC14")
		)
		(pad "45" smd rect
			(at 3.750056 1.75006 270)
			(size 0.2794 1.6002)
			(layers "F.Cu" "F.Mask" "F.Paste")
			(net "GND")
		)
		(pad "46" smd rect
			(at -3.800094 1.999996 270)
			(size 0.2794 1.6002)
			(layers "F.Cu" "F.Mask" "F.Paste")
			(net "NC_M2_0_NC15")
		)
		(pad "47" smd rect
			(at 3.750056 2.249932 270)
			(size 0.2794 1.6002)
			(layers "F.Cu" "F.Mask" "F.Paste")
			(net "P3E_PCH_M2_TX_C_DP<3>")
		)
		(pad "48" smd rect
			(at -3.800094 2.500122 270)
			(size 0.2794 1.6002)
			(layers "F.Cu" "F.Mask" "F.Paste")
			(net "NC_M2_0_NC16")
		)
		(pad "49" smd rect
			(at 3.750056 2.750058 270)
			(size 0.2794 1.6002)
			(layers "F.Cu" "F.Mask" "F.Paste")
			(net "P3E_PCH_M2_TX_C_DN<3>")
		)
		(pad "50" smd rect
			(at -3.800094 2.999994 270)
			(size 0.2794 1.6002)
			(layers "F.Cu" "F.Mask" "F.Paste")
			(net "RST_PCIE_PCH_DEV_0_N")
		)
		(pad "51" smd rect
			(at 3.750056 3.24993 270)
			(size 0.2794 1.6002)
			(layers "F.Cu" "F.Mask" "F.Paste")
			(net "GND")
		)
		(pad "52" smd rect
			(at -3.800094 3.50012 270)
			(size 0.2794 1.6002)
			(layers "F.Cu" "F.Mask" "F.Paste")
			(net "M2_SSD0_CLKREQ_EN_N_BUF")
		)
		(pad "53" smd rect
			(at 3.750056 3.750056 270)
			(size 0.2794 1.6002)
			(layers "F.Cu" "F.Mask" "F.Paste")
			(net "CLK_100M_PE_M2_0_DN")
		)
		(pad "54" smd rect
			(at -3.800094 3.999992 270)
			(size 0.2794 1.6002)
			(layers "F.Cu" "F.Mask" "F.Paste")
			(net "M2_0_PEWAKE_N")
		)
		(pad "55" smd rect
			(at 3.750056 4.249928 270)
			(size 0.2794 1.6002)
			(layers "F.Cu" "F.Mask" "F.Paste")
			(net "CLK_100M_PE_M2_0_DP")
		)
		(pad "56" smd rect
			(at -3.800094 4.500118 270)
			(size 0.2794 1.6002)
			(layers "F.Cu" "F.Mask" "F.Paste")
			(net "NC_M2_0_NC17")
		)
		(pad "57" smd rect
			(at 3.750056 4.750054 270)
			(size 0.2794 1.6002)
			(layers "F.Cu" "F.Mask" "F.Paste")
			(net "GND")
		)
		(pad "58" smd rect
			(at -3.800094 4.99999 270)
			(size 0.2794 1.6002)
			(layers "F.Cu" "F.Mask" "F.Paste")
			(net "NC_M2_0_NC18")
		)
		(pad "67" smd rect
			(at 3.750056 7.249922 270)
			(size 0.2794 1.6002)
			(layers "F.Cu" "F.Mask" "F.Paste")
			(net "NC_M2_0_NC19")
		)
		(pad "68" smd rect
			(at -3.800094 7.500112 270)
			(size 0.2794 1.6002)
			(layers "F.Cu" "F.Mask" "F.Paste")
			(net "NC_M2_0_SUSCLK")
		)
		(pad "69" smd rect
			(at 3.750056 7.750048 270)
			(size 0.2794 1.6002)
			(layers "F.Cu" "F.Mask" "F.Paste")
			(net "FM_M2_SSD_0_PEDET")
		)
		(pad "70" smd rect
			(at -3.800094 7.999984 270)
			(size 0.2794 1.6002)
			(layers "F.Cu" "F.Mask" "F.Paste")
			(net "P3V3_M2_0")
		)
		(pad "71" smd rect
			(at 3.750056 8.24992 270)
			(size 0.2794 1.6002)
			(layers "F.Cu" "F.Mask" "F.Paste")
			(net "GND")
		)
		(pad "72" smd rect
			(at -3.800094 8.50011 270)
			(size 0.2794 1.6002)
			(layers "F.Cu" "F.Mask" "F.Paste")
			(net "P3V3_M2_0")
		)
		(pad "73" smd rect
			(at 3.750056 8.750046 270)
			(size 0.2794 1.6002)
			(layers "F.Cu" "F.Mask" "F.Paste")
			(net "GND")
		)
		(pad "74" smd rect
			(at -3.800094 8.999982 270)
			(size 0.2794 1.6002)
			(layers "F.Cu" "F.Mask" "F.Paste")
			(net "P3V3_M2_0")
		)
		(pad "75" smd rect
			(at 3.750056 9.249918 270)
			(size 0.2794 1.6002)
			(layers "F.Cu" "F.Mask" "F.Paste")
			(net "GND")
		)
		(pad "G1" smd rect
			(at 2.975102 -10.349992 270)
			(size 1.2446 2.794)
			(layers "F.Cu" "F.Mask" "F.Paste")
			(net "GND")
		)
		(pad "G2" smd rect
			(at 2.975102 10.349992 270)
			(size 1.2446 2.794)
			(layers "F.Cu" "F.Mask" "F.Paste")
			(net "GND")
		)
	)
)
